(kicad_pcb
	(version 20260206)
	(generator "pcbnew")
	(generator_version "10.0")
	(general
		(thickness 1.6)
		(legacy_teardrops no)
	)
	(paper "A4")
	(title_block
		(title "fcb — Lightning_FCB_BRD.brd")
		(comment 1 "Lightning (Wiwynn / Facebook NVMe JBOF) / footprints 1-4 of 495")
	)
	(layers
		(0 "F.Cu" signal "TOP")
		(4 "In1.Cu" signal "L2GND")
		(6 "In2.Cu" signal "L3VCC")
		(2 "B.Cu" signal "BOTTOM")
		(9 "F.Adhes" user "F.Adhesive")
		(11 "B.Adhes" user "B.Adhesive")
		(13 "F.Paste" user "Package Geometry/Pastemask Top")
		(15 "B.Paste" user "Package Geometry/Pastemask Bottom")
		(5 "F.SilkS" user "Ref Des/Silkscreen Top")
		(7 "B.SilkS" user "Ref Des/Silkscreen Bottom")
		(1 "F.Mask" user "Board Geometry/Soldermask Top")
		(3 "B.Mask" user "Board Geometry/Soldermask Bottom")
		(17 "Dwgs.User" user "User.Drawings")
		(19 "Cmts.User" user "User.Comments")
		(21 "Eco1.User" user "User.Eco1")
		(23 "Eco2.User" user "User.Eco2")
		(25 "Edge.Cuts" user "Board Geometry/Outline")
		(27 "Margin" user)
		(31 "F.CrtYd" user "Package Geometry/Place Bound Top")
		(29 "B.CrtYd" user "Package Geometry/Place Bound Bottom")
		(35 "F.Fab" user "Ref Des/Assembly Top")
		(33 "B.Fab" user "Ref Des/Assembly Bottom")
	)
	(footprint ""
		(layer "F.Cu")
		(at 34.716466 -141.089634 180)
		(property "Reference" "PR107"
			(at 0 0 180)
			(layer "F.SilkS")
			(hide yes)
			(effects
				(font
					(size 1.27 1.27)
				)
			)
		)
		(property "Value" "1KR2F-3-GP"
			(at 0.064008 -3.993896 180)
			(unlocked yes)
			(layer "F.Fab")
			(hide yes)
			(effects
				(font
					(size 1.016 1.016)
					(thickness 0.1524)
				)
			)
		)
		(property "Device Type" "R402H16"
			(at 0.064008 -5.517896 180)
			(unlocked yes)
			(layer "F.Fab")
			(hide yes)
			(effects
				(font
					(size 1.016 1.016)
					(thickness 0.1524)
				)
			)
		)
		(duplicate_pad_numbers_are_jumpers no)
		(fp_line
			(start 0.508 -0.9398)
			(end -0.508 -0.9398)
			(stroke
				(width 0.1524)
				(type default)
			)
			(layer "F.SilkS")
		)
		(fp_line
			(start -0.508 -0.9398)
			(end -0.508 0.9398)
			(stroke
				(width 0.1524)
				(type default)
			)
			(layer "F.SilkS")
		)
		(fp_rect
			(start -0.508 0.9398)
			(end 0.508 -0.9398)
			(stroke
				(width 0)
				(type default)
			)
			(fill no)
			(layer "F.CrtYd")
		)
		(fp_rect
			(start -0.508 0.9398)
			(end 0.508 -0.9398)
			(stroke
				(width 0)
				(type default)
			)
			(fill no)
			(layer "F.Fab")
		)
		(pad "1" smd custom
			(at 0 -0.4445 180)
			(size 0.1397 0.1397)
			(layers "F.Cu" "F.Mask" "F.Paste")
			(net "P12VL_2490_PG")
			(options
				(clearance outline)
				(anchor circle)
			)
			(primitives
				(gr_poly
					(pts
						(arc
							(start -0.1778 -0.2794)
							(mid -0.249642 -0.249642)
							(end -0.2794 -0.1778)
						)
						(arc
							(start -0.2794 0.1778)
							(mid -0.249642 0.249642)
							(end -0.1778 0.2794)
						)
						(arc
							(start 0.1778 0.2794)
							(mid 0.249642 0.249642)
							(end 0.2794 0.1778)
						)
						(arc
							(start 0.2794 -0.1778)
							(mid 0.249642 -0.249642)
							(end 0.1778 -0.2794)
						)
					)
					(width 0)
					(fill yes)
				)
			)
		)
		(pad "2" smd custom
			(at 0 0.4445 180)
			(size 0.1397 0.1397)
			(layers "F.Cu" "F.Mask" "F.Paste")
			(net "GND")
			(options
				(clearance outline)
				(anchor circle)
			)
			(primitives
				(gr_poly
					(pts
						(arc
							(start -0.1778 -0.2794)
							(mid -0.249642 -0.249642)
							(end -0.2794 -0.1778)
						)
						(arc
							(start -0.2794 0.1778)
							(mid -0.249642 0.249642)
							(end -0.1778 0.2794)
						)
						(arc
							(start 0.1778 0.2794)
							(mid 0.249642 0.249642)
							(end 0.2794 0.1778)
						)
						(arc
							(start 0.2794 -0.1778)
							(mid 0.249642 -0.249642)
							(end 0.1778 -0.2794)
						)
					)
					(width 0)
					(fill yes)
				)
			)
		)
	)
	(footprint ""
		(layer "F.Cu")
		(at 5.993384 -65.735962 180)
		(property "Reference" "Q3"
			(at 0 0 180)
			(layer "F.SilkS")
			(hide yes)
			(effects
				(font
					(size 1.27 1.27)
				)
			)
		)
		(property "Value" "PMBS3904-1-GP"
			(at 0 -9.0932 180)
			(unlocked yes)
			(layer "F.Fab")
			(hide yes)
			(effects
				(font
					(size 1.016 1.016)
					(thickness 0.1524)
				)
			)
		)
		(property "Device Type" "SOT-23-10H44"
			(at 0 -10.6172 180)
			(unlocked yes)
			(layer "F.Fab")
			(hide yes)
			(effects
				(font
					(size 1.016 1.016)
					(thickness 0.1524)
				)
			)
		)
		(duplicate_pad_numbers_are_jumpers no)
		(fp_line
			(start 1.651 1.778)
			(end 1.651 -1.778)
			(stroke
				(width 0.1524)
				(type default)
			)
			(layer "F.SilkS")
		)
		(fp_line
			(start 1.651 -1.778)
			(end -1.651 -1.778)
			(stroke
				(width 0.1524)
				(type default)
			)
			(layer "F.SilkS")
		)
		(fp_line
			(start -0.635 1.8796)
			(end -1.7526 1.8796)
			(stroke
				(width 0.3302)
				(type default)
			)
			(layer "F.SilkS")
		)
		(fp_line
			(start -0.71628 2.15265)
			(end -1.26492 2.15265)
			(stroke
				(width 0.0127)
				(type default)
			)
			(layer "F.SilkS")
		)
		(fp_line
			(start -0.719074 2.145538)
			(end -1.265936 2.14122)
			(stroke
				(width 0.0127)
				(type default)
			)
			(layer "F.SilkS")
		)
		(fp_line
			(start -0.9906 1.86309)
			(end -0.701294 2.15265)
			(stroke
				(width 0.0127)
				(type default)
			)
			(layer "F.SilkS")
		)
		(fp_line
			(start -0.994156 1.8669)
			(end -0.987044 1.8669)
			(stroke
				(width 0.0127)
				(type default)
			)
			(layer "F.SilkS")
		)
		(fp_line
			(start -1.003808 1.876552)
			(end -0.977646 1.876552)
			(stroke
				(width 0.0127)
				(type default)
			)
			(layer "F.SilkS")
		)
		(fp_line
			(start -1.013206 1.88595)
			(end -0.967994 1.88595)
			(stroke
				(width 0.0127)
				(type default)
			)
			(layer "F.SilkS")
		)
		(fp_line
			(start -1.022858 1.895602)
			(end -0.958596 1.895602)
			(stroke
				(width 0.0127)
				(type default)
			)
			(layer "F.SilkS")
		)
		(fp_line
			(start -1.032256 1.905)
			(end -0.948944 1.905)
			(stroke
				(width 0.0127)
				(type default)
			)
			(layer "F.SilkS")
		)
		(fp_line
			(start -1.041908 1.914652)
			(end -0.939546 1.914652)
			(stroke
				(width 0.0127)
				(type default)
			)
			(layer "F.SilkS")
		)
		(fp_line
			(start -1.051306 1.92405)
			(end -0.929894 1.92405)
			(stroke
				(width 0.0127)
				(type default)
			)
			(layer "F.SilkS")
		)
		(fp_line
			(start -1.060958 1.933702)
			(end -0.920496 1.933702)
			(stroke
				(width 0.0127)
				(type default)
			)
			(layer "F.SilkS")
		)
		(fp_line
			(start -1.070356 1.9431)
			(end -0.910844 1.9431)
			(stroke
				(width 0.0127)
				(type default)
			)
			(layer "F.SilkS")
		)
		(fp_line
			(start -1.080008 1.952752)
			(end -0.901446 1.952752)
			(stroke
				(width 0.0127)
				(type default)
			)
			(layer "F.SilkS")
		)
		(fp_line
			(start -1.089406 1.96215)
			(end -0.891794 1.96215)
			(stroke
				(width 0.0127)
				(type default)
			)
			(layer "F.SilkS")
		)
		(fp_line
			(start -1.099058 1.971802)
			(end -0.882396 1.971802)
			(stroke
				(width 0.0127)
				(type default)
			)
			(layer "F.SilkS")
		)
		(fp_line
			(start -1.108456 1.9812)
			(end -0.872744 1.9812)
			(stroke
				(width 0.0127)
				(type default)
			)
			(layer "F.SilkS")
		)
		(fp_line
			(start -1.118108 1.990852)
			(end -0.863346 1.990852)
			(stroke
				(width 0.0127)
				(type default)
			)
			(layer "F.SilkS")
		)
		(fp_line
			(start -1.127506 2.00025)
			(end -0.853694 2.00025)
			(stroke
				(width 0.0127)
				(type default)
			)
			(layer "F.SilkS")
		)
		(fp_line
			(start -1.137158 2.009902)
			(end -0.844296 2.009902)
			(stroke
				(width 0.0127)
				(type default)
			)
			(layer "F.SilkS")
		)
		(fp_line
			(start -1.146556 2.0193)
			(end -0.834644 2.0193)
			(stroke
				(width 0.0127)
				(type default)
			)
			(layer "F.SilkS")
		)
		(fp_line
			(start -1.156208 2.028952)
			(end -0.825246 2.028952)
			(stroke
				(width 0.0127)
				(type default)
			)
			(layer "F.SilkS")
		)
		(fp_line
			(start -1.165606 2.03835)
			(end -0.815594 2.03835)
			(stroke
				(width 0.0127)
				(type default)
			)
			(layer "F.SilkS")
		)
		(fp_line
			(start -1.175258 2.048002)
			(end -0.806196 2.048002)
			(stroke
				(width 0.0127)
				(type default)
			)
			(layer "F.SilkS")
		)
		(fp_line
			(start -1.184656 2.0574)
			(end -0.796544 2.0574)
			(stroke
				(width 0.0127)
				(type default)
			)
			(layer "F.SilkS")
		)
		(fp_line
			(start -1.194308 2.067052)
			(end -0.787146 2.067052)
			(stroke
				(width 0.0127)
				(type default)
			)
			(layer "F.SilkS")
		)
		(fp_line
			(start -1.203706 2.07645)
			(end -0.777494 2.07645)
			(stroke
				(width 0.0127)
				(type default)
			)
			(layer "F.SilkS")
		)
		(fp_line
			(start -1.213358 2.086102)
			(end -0.768096 2.086102)
			(stroke
				(width 0.0127)
				(type default)
			)
			(layer "F.SilkS")
		)
		(fp_line
			(start -1.222756 2.0955)
			(end -0.758444 2.0955)
			(stroke
				(width 0.0127)
				(type default)
			)
			(layer "F.SilkS")
		)
		(fp_line
			(start -1.232408 2.105152)
			(end -0.749046 2.105152)
			(stroke
				(width 0.0127)
				(type default)
			)
			(layer "F.SilkS")
		)
		(fp_line
			(start -1.241806 2.11455)
			(end -0.739394 2.11455)
			(stroke
				(width 0.0127)
				(type default)
			)
			(layer "F.SilkS")
		)
		(fp_line
			(start -1.251458 2.124202)
			(end -0.729996 2.124202)
			(stroke
				(width 0.0127)
				(type default)
			)
			(layer "F.SilkS")
		)
		(fp_line
			(start -1.260856 2.1336)
			(end -0.720344 2.1336)
			(stroke
				(width 0.0127)
				(type default)
			)
			(layer "F.SilkS")
		)
		(fp_line
			(start -1.279144 2.15265)
			(end -0.701294 2.15265)
			(stroke
				(width 0.0127)
				(type default)
			)
			(layer "F.SilkS")
		)
		(fp_line
			(start -1.279398 2.152142)
			(end -0.9906 1.86309)
			(stroke
				(width 0.0127)
				(type default)
			)
			(layer "F.SilkS")
		)
		(fp_line
			(start -1.651 1.778)
			(end 1.651 1.778)
			(stroke
				(width 0.1524)
				(type default)
			)
			(layer "F.SilkS")
		)
		(fp_line
			(start -1.651 -1.778)
			(end -1.651 1.778)
			(stroke
				(width 0.1524)
				(type default)
			)
			(layer "F.SilkS")
		)
		(fp_line
			(start -1.7526 1.8796)
			(end -1.7526 0.9906)
			(stroke
				(width 0.3302)
				(type default)
			)
			(layer "F.SilkS")
		)
		(fp_poly
			(pts
				(xy -1.285748 2.159) (xy -1.285748 1.8796) (xy -1.778 1.8796) (xy -1.778 -1.8796) (xy 1.778 -1.8796)
				(xy 1.778 1.8796) (xy -0.694944 1.8796) (xy -0.694944 2.159)
			)
			(stroke
				(width 0)
				(type default)
			)
			(fill no)
			(layer "F.CrtYd")
		)
		(fp_poly
			(pts
				(xy -1.285748 2.159) (xy -1.285748 1.8796) (xy -1.778 1.8796) (xy -1.778 -1.8796) (xy 1.778 -1.8796)
				(xy 1.778 1.8796) (xy -0.694944 1.8796) (xy -0.694944 2.159)
			)
			(stroke
				(width 0)
				(type default)
			)
			(fill no)
			(layer "F.Fab")
		)
		(pad "1" smd rect
			(at -0.98425 0.9525 180)
			(size 0.762 1.143)
			(layers "F.Cu" "F.Mask" "F.Paste")
			(net "LED_DR_LED5_B")
		)
		(pad "2" smd rect
			(at 0.98425 0.9525 180)
			(size 0.762 1.143)
			(layers "F.Cu" "F.Mask" "F.Paste")
			(net "GND")
		)
		(pad "3" smd rect
			(at 0 -0.9525 180)
			(size 0.762 1.143)
			(layers "F.Cu" "F.Mask" "F.Paste")
			(net "LED_DR_LED5_BLUE")
		)
	)
	(footprint ""
		(layer "F.Cu")
		(at 21.7678 -219.8878 90)
		(property "Reference" "R135"
			(at 0 0 90)
			(layer "F.SilkS")
			(hide yes)
			(effects
				(font
					(size 1.27 1.27)
				)
			)
		)
		(property "Value" "4K7R2F-GP"
			(at 0.064008 -3.993896 90)
			(unlocked yes)
			(layer "F.Fab")
			(hide yes)
			(effects
				(font
					(size 1.016 1.016)
					(thickness 0.1524)
				)
			)
		)
		(property "Device Type" "R402H16"
			(at 0.064008 -5.517896 90)
			(unlocked yes)
			(layer "F.Fab")
			(hide yes)
			(effects
				(font
					(size 1.016 1.016)
					(thickness 0.1524)
				)
			)
		)
		(duplicate_pad_numbers_are_jumpers no)
		(fp_line
			(start 0.508 -0.9398)
			(end -0.508 -0.9398)
			(stroke
				(width 0.1524)
				(type default)
			)
			(layer "F.SilkS")
		)
		(fp_line
			(start -0.508 -0.9398)
			(end -0.508 0.9398)
			(stroke
				(width 0.1524)
				(type default)
			)
			(layer "F.SilkS")
		)
		(fp_rect
			(start -0.508 0.9398)
			(end 0.508 -0.9398)
			(stroke
				(width 0)
				(type default)
			)
			(fill no)
			(layer "F.CrtYd")
		)
		(fp_rect
			(start -0.508 0.9398)
			(end 0.508 -0.9398)
			(stroke
				(width 0)
				(type default)
			)
			(fill no)
			(layer "F.Fab")
		)
		(pad "1" smd custom
			(at 0 -0.4445 90)
			(size 0.1397 0.1397)
			(layers "F.Cu" "F.Mask" "F.Paste")
			(net "P3V3")
			(options
				(clearance outline)
				(anchor circle)
			)
			(primitives
				(gr_poly
					(pts
						(arc
							(start -0.1778 -0.2794)
							(mid -0.249642 -0.249642)
							(end -0.2794 -0.1778)
						)
						(arc
							(start -0.2794 0.1778)
							(mid -0.249642 0.249642)
							(end -0.1778 0.2794)
						)
						(arc
							(start 0.1778 0.2794)
							(mid 0.249642 0.249642)
							(end 0.2794 0.1778)
						)
						(arc
							(start 0.2794 -0.1778)
							(mid 0.249642 -0.249642)
							(end 0.1778 -0.2794)
						)
					)
					(width 0)
					(fill yes)
				)
			)
		)
		(pad "2" smd custom
			(at 0 0.4445 90)
			(size 0.1397 0.1397)
			(layers "F.Cu" "F.Mask" "F.Paste")
			(net "PWM_OUT_FAN1")
			(options
				(clearance outline)
				(anchor circle)
			)
			(primitives
				(gr_poly
					(pts
						(arc
							(start -0.1778 -0.2794)
							(mid -0.249642 -0.249642)
							(end -0.2794 -0.1778)
						)
						(arc
							(start -0.2794 0.1778)
							(mid -0.249642 0.249642)
							(end -0.1778 0.2794)
						)
						(arc
							(start 0.1778 0.2794)
							(mid 0.249642 0.249642)
							(end 0.2794 0.1778)
						)
						(arc
							(start 0.2794 -0.1778)
							(mid 0.249642 -0.249642)
							(end 0.1778 -0.2794)
						)
					)
					(width 0)
					(fill yes)
				)
			)
		)
	)
	(footprint ""
		(layer "F.Cu")
		(at 4.040124 -193.339974 -90)
		(property "Reference" "CN4"
			(at 0 0 270)
			(layer "F.SilkS")
			(hide yes)
			(effects
				(font
					(size 1.27 1.27)
				)
			)
		)
		(property "Value" "JWT-CON5-42-GP"
			(at -7.8105 2.9591 270)
			(unlocked yes)
			(layer "F.Fab")
			(hide yes)
			(effects
				(font
					(size 1.016 1.016)
					(thickness 0.1524)
				)
			)
		)
		(property "Device Type" "A2541WR0-1TX5PA-6T-0E"
			(at -7.8105 1.4351 270)
			(unlocked yes)
			(layer "F.Fab")
			(hide yes)
			(effects
				(font
					(size 1.016 1.016)
					(thickness 0.1524)
				)
			)
		)
		(duplicate_pad_numbers_are_jumpers no)
		(fp_line
			(start -6.604 10.287)
			(end 6.604 10.287)
			(stroke
				(width 0.1524)
				(type default)
			)
			(layer "F.SilkS")
		)
		(fp_line
			(start 6.604 10.287)
			(end 6.604 -0.9652)
			(stroke
				(width 0.1524)
				(type default)
			)
			(layer "F.SilkS")
		)
		(fp_line
			(start -6.604 -0.9652)
			(end -6.604 10.287)
			(stroke
				(width 0.1524)
				(type default)
			)
			(layer "F.SilkS")
		)
		(fp_line
			(start 6.604 -0.9652)
			(end -6.604 -0.9652)
			(stroke
				(width 0.1524)
				(type default)
			)
			(layer "F.SilkS")
		)
		(fp_line
			(start -6.731 -1.0922)
			(end -6.731 0.1778)
			(stroke
				(width 0.4064)
				(type default)
			)
			(layer "F.SilkS")
		)
		(fp_line
			(start -5.461 -1.0922)
			(end -6.731 -1.0922)
			(stroke
				(width 0.4064)
				(type default)
			)
			(layer "F.SilkS")
		)
		(fp_circle
			(center -5.08 0)
			(end -5.08 -1.0668)
			(stroke
				(width 0.3048)
				(type default)
			)
			(fill no)
			(layer "F.SilkS")
		)
		(fp_circle
			(center -2.54 0)
			(end -2.54 -1.0668)
			(stroke
				(width 0.3048)
				(type default)
			)
			(fill no)
			(layer "F.SilkS")
		)
		(fp_circle
			(center 0 0)
			(end 0 -1.0668)
			(stroke
				(width 0.3048)
				(type default)
			)
			(fill no)
			(layer "F.SilkS")
		)
		(fp_circle
			(center 2.54 0)
			(end 2.54 -1.0668)
			(stroke
				(width 0.3048)
				(type default)
			)
			(fill no)
			(layer "F.SilkS")
		)
		(fp_circle
			(center 5.08 0)
			(end 5.08 -1.0668)
			(stroke
				(width 0.3048)
				(type default)
			)
			(fill no)
			(layer "F.SilkS")
		)
		(fp_rect
			(start -6.35 10.033)
			(end 6.35 -0.3302)
			(stroke
				(width 0)
				(type default)
			)
			(fill no)
			(layer "F.CrtYd")
		)
		(fp_poly
			(pts
				(xy -6.35 -0.3302) (xy 6.858 -0.3302) (xy 6.858 -1.2192) (xy -6.858 -1.2192) (xy -6.858 10.541)
				(xy 6.858 10.541) (xy 6.858 -0.3175) (xy 6.35 -0.3175) (xy 6.35 10.033) (xy -6.35 10.033)
			)
			(stroke
				(width 0)
				(type default)
			)
			(fill no)
			(layer "F.CrtYd")
		)
		(fp_rect
			(start -6.858 10.541)
			(end 6.858 -1.2192)
			(stroke
				(width 0)
				(type default)
			)
			(fill no)
			(layer "F.Fab")
		)
		(pad "1" thru_hole circle
			(at -5.08 0 270)
			(size 1.4224 1.4224)
			(drill 1.016)
			(layers "*.Cu" "*.Mask")
			(remove_unused_layers no)
			(net "GND")
			(clearance 0.1524)
			(thermal_gap 0.1524)
		)
		(pad "2" thru_hole circle
			(at -2.54 0 270)
			(size 1.4224 1.4224)
			(drill 1.016)
			(layers "*.Cu" "*.Mask")
			(remove_unused_layers no)
			(net "P12V_FAN4")
			(clearance 0.1524)
			(thermal_gap 0.1524)
		)
		(pad "3" thru_hole circle
			(at 0 0 270)
			(size 1.4224 1.4224)
			(drill 1.016)
			(layers "*.Cu" "*.Mask")
			(remove_unused_layers no)
			(net "FAN_TACH8")
			(clearance 0.1524)
			(thermal_gap 0.1524)
		)
		(pad "4" thru_hole circle
			(at 2.54 0 270)
			(size 1.4224 1.4224)
			(drill 1.016)
			(layers "*.Cu" "*.Mask")
			(remove_unused_layers no)
			(net "PWM_OUT_FAN4_NET")
			(clearance 0.1524)
			(thermal_gap 0.1524)
		)
		(pad "5" thru_hole circle
			(at 5.08 0 270)
			(size 1.4224 1.4224)
			(drill 1.016)
			(layers "*.Cu" "*.Mask")
			(remove_unused_layers no)
			(net "FAN_TACH7")
			(clearance 0.1524)
			(thermal_gap 0.1524)
		)
	)
)
